FILE_TYPE = MACRO_DRAWING;
SET COLOR_WIRE YELLOW;
SET COLOR_PROP ORANGE;
SET COLOR_DOT WHITE;
SET COLOR_ARC YELLOW;
SET COLOR_BODY GREEN;
SET COLOR_NOTE PURPLE;
SET PROP_DISPLAY VALUE;
SET PAGE_NUMBER P131;
FORCEADD QUANTA_TITLE_BLOCK_C..1
(0 0);
FORCEPROP 1 LAST CUSTOM_TXT_CDS <NAME_2>
J 0
(-3175 50);
FORCEPROP 1 LAST CUSTOM_TXT_CDS <NAME_1>
J 0
(-3175 175);
FORCEPROP 1 LAST CUSTOM_TXT_CDS <Q_NUMBER>
J 0
(-1403 103);
DISPLAY 1.212766 (-1403 103);
FORCEPROP 1 LAST CUSTOM_TXT_CDS <Q_PROJ>
J 0
(-2382 102);
DISPLAY 1.212766 (-2382 102);
FORCEPROP 1 LAST CUSTOM_TXT_CDS <Q_REV>
J 0
(-184 103);
DISPLAY 1.212766 (-184 103);
FORCEPROP 1 LAST CUSTOM_TXT_CDS <CON_LAST_MODIFIED>
J 0
(-1885 15);
DISPLAY 0.978723 (-1885 15);
FORCEPROP 1 LAST CUSTOM_TXT_CDS <CON_PAGE_NUM> OF <CON_TOTAL_PAGES>
J 0
(-446 18);
DISPLAY 0.978723 (-446 18);
FORCEPROP 1 LAST Q_TITLE Blank
J 0
(-9300 50);
DISPLAY 2.446809 (-9300 50);
PAINT GREEN (-9300 50);
FORCEPROP 2 LAST CDS_LIB pure_quanta
J 0
(0 0);
DISPLAY INVISIBLE (0 0);
FORCEPROP 1 LAST CDS_LMAN_SYM_OUTLINE -9475,6775,100,-125
J 0
(0 0);
DISPLAY 0.468085 (0 0);
PAINT GREEN (0 0);
DISPLAY INVISIBLE (0 0);
FORCEPROP 2 LAST PAGE_BORDER TRUE
J 0
(-7890 5250);
DISPLAY 0.638298 (-7890 5250);
PAINT PINK (-7890 5250);
DISPLAY INVISIBLE (-7890 5250);
FORCEPROP 2 LAST CDS_XR_PAGE_TITLE CR-154 : @T6G_MB_LIB.T6G(SCH_1):PAGE154
J 0
(-7890 5250);
DISPLAY 0.638298 (-7890 5250);
PAINT PINK (-7890 5250);
DISPLAY INVISIBLE (-7890 5250);
FORCEPROP 2 LAST CUSTOM_TXT_CDS <XR_PAGE_TITLE>
J 0
(-7890 5250);
DISPLAY 0.638298 (-7890 5250);
PAINT PINK (-7890 5250);
DISPLAY INVISIBLE (-7890 5250);
FORCEPROP 1 LAST COMMENT_BODY TRUE
J 0
(12 -13);
DISPLAY 0.978723 (12 -13);
PAINT GREEN (12 -13);
DISPLAY INVISIBLE (12 -13);
FORCEPROP 1 LAST Q_DEPT BU9
J 1
(-3763 49);
DISPLAY 1.957447 (-3763 49);
PAINT GREEN (-3763 49);
DISPLAY INVISIBLE (-3763 49);
FORCEPROP 0 LAST CDS_CON_LAST_MODIFIED Thu Aug 24 10:14:42 2023
J 0
(-1885 15);
DISPLAY INVISIBLE (-1885 15);
QUIT
